# SCM (Grand Teton) — schematic netlist excerpt (pin names and nets, part order shuffled) for the footprints in the layout excerpt that follows; sources: Cadence DE-HDL packaged netlist, KiCad conversion of 12092022_DA0F0TMDCD0_F0T_Management_Board_D_brd_V3_OCP.brd

C12  Q_CAP  0.22UF 16V 10% X7R  pkg 0402  page 20 : A = M_BMC_DDR4_MCLK_C ; B = GND
R695  Q_RES  0 5% CHIP  pkg 0402LF  page 47 : A = LED_POSTCODE_4 ; B = LED_POSTCODE_4_R1

(kicad_pcb
	(version 20260206)
	(generator "pcbnew")
	(generator_version "10.0")
	(general
		(thickness 1.6)
		(legacy_teardrops no)
	)
	(paper "A4")
	(title_block
		(title "12092022_DA0F0TMDCD0_F0T_Management_Board_D_brd_V3_OCP.brd")
		(comment 1 "Grand Teton / footprints 1101-1102 of 1440")
	)
	(layers
		(0 "F.Cu" signal "TOP")
		(4 "In1.Cu" signal "GND")
		(6 "In2.Cu" signal "IN1")
		(8 "In3.Cu" signal "GND1")
		(10 "In4.Cu" signal "IN2")
		(12 "In5.Cu" signal "VCC")
		(14 "In6.Cu" signal "VCC1")
		(16 "In7.Cu" signal "IN3")
		(18 "In8.Cu" signal "GND2")
		(20 "In9.Cu" signal "IN4")
		(22 "In10.Cu" signal "GND3")
		(2 "B.Cu" signal "BOTTOM")
		(9 "F.Adhes" user "F.Adhesive")
		(11 "B.Adhes" user "B.Adhesive")
		(13 "F.Paste" user "Package Geometry/Pastemask Top")
		(15 "B.Paste" user "Package Geometry/Pastemask Bottom")
		(5 "F.SilkS" user "Ref Des/Silkscreen Top")
		(7 "B.SilkS" user "Ref Des/Silkscreen Bottom")
		(1 "F.Mask" user "Board Geometry/Soldermask Top")
		(3 "B.Mask" user "Board Geometry/Soldermask Bottom")
		(17 "Dwgs.User" user "User.Drawings")
		(19 "Cmts.User" user "User.Comments")
		(21 "Eco1.User" user "User.Eco1")
		(23 "Eco2.User" user "User.Eco2")
		(25 "Edge.Cuts" user "Board Geometry/Outline")
		(27 "Margin" user)
		(31 "F.CrtYd" user "Package Geometry/Place Bound Top")
		(29 "B.CrtYd" user "Package Geometry/Place Bound Bottom")
		(35 "F.Fab" user "Ref Des/Assembly Top")
		(33 "B.Fab" user "Ref Des/Assembly Bottom")
	)
	(footprint ""
		(layer "B.Cu")
		(at 76.582778 -48.63084 -90)
		(property "Reference" "C12"
			(at 0 0 90)
			(layer "B.SilkS")
			(hide yes)
			(effects
				(font
					(size 1.27 1.27)
				)
				(justify mirror)
			)
		)
		(property "Value" ""
			(at 0 0 90)
			(layer "B.Fab")
			(effects
				(font
					(size 1.27 1.27)
				)
				(justify mirror)
			)
		)
		(duplicate_pad_numbers_are_jumpers no)
		(fp_line
			(start -0.7874 0.4064)
			(end 0.7874 0.4064)
			(stroke
				(width 0.1524)
				(type default)
			)
			(layer "B.SilkS")
		)
		(fp_line
			(start 0.7874 0.4064)
			(end 0.7874 -0.4064)
			(stroke
				(width 0.1524)
				(type default)
			)
			(layer "B.SilkS")
		)
		(fp_line
			(start -0.7874 -0.4064)
			(end -0.7874 0.4064)
			(stroke
				(width 0.1524)
				(type default)
			)
			(layer "B.SilkS")
		)
		(fp_line
			(start 0.7874 -0.4064)
			(end -0.7874 -0.4064)
			(stroke
				(width 0.1524)
				(type default)
			)
			(layer "B.SilkS")
		)
		(fp_line
			(start -0.67945 0.3048)
			(end -0.120396 0.3048)
			(stroke
				(width 0.1)
				(type default)
			)
			(layer "B.Fab")
		)
		(fp_line
			(start -0.120396 0.3048)
			(end -0.120396 0.2794)
			(stroke
				(width 0.1)
				(type default)
			)
			(layer "B.Fab")
		)
		(fp_line
			(start 0.12065 0.3048)
			(end 0.67945 0.3048)
			(stroke
				(width 0.1)
				(type default)
			)
			(layer "B.Fab")
		)
		(fp_line
			(start 0.67945 0.3048)
			(end 0.67945 -0.305054)
			(stroke
				(width 0.1)
				(type default)
			)
			(layer "B.Fab")
		)
		(fp_line
			(start -0.120396 0.2794)
			(end 0.12065 0.2794)
			(stroke
				(width 0.1)
				(type default)
			)
			(layer "B.Fab")
		)
		(fp_line
			(start 0.12065 0.2794)
			(end 0.12065 0.3048)
			(stroke
				(width 0.1)
				(type default)
			)
			(layer "B.Fab")
		)
		(fp_line
			(start -0.12065 -0.2794)
			(end -0.12065 -0.3048)
			(stroke
				(width 0.1)
				(type default)
			)
			(layer "B.Fab")
		)
		(fp_line
			(start 0.12065 -0.2794)
			(end -0.12065 -0.2794)
			(stroke
				(width 0.1)
				(type default)
			)
			(layer "B.Fab")
		)
		(fp_line
			(start -0.67945 -0.3048)
			(end -0.67945 0.3048)
			(stroke
				(width 0.1)
				(type default)
			)
			(layer "B.Fab")
		)
		(fp_line
			(start -0.12065 -0.3048)
			(end -0.67945 -0.3048)
			(stroke
				(width 0.1)
				(type default)
			)
			(layer "B.Fab")
		)
		(fp_line
			(start 0.12065 -0.305054)
			(end 0.12065 -0.2794)
			(stroke
				(width 0.1)
				(type default)
			)
			(layer "B.Fab")
		)
		(fp_line
			(start 0.67945 -0.305054)
			(end 0.12065 -0.305054)
			(stroke
				(width 0.1)
				(type default)
			)
			(layer "B.Fab")
		)
		(pad "1" smd circle
			(at 0.40005 0 90)
			(size 0 0)
			(layers "B.Cu" "B.Mask" "B.Paste")
			(net "M_BMC_DDR4_MCLK_C")
		)
		(pad "2" smd circle
			(at -0.40005 0 90)
			(size 0 0)
			(layers "B.Cu" "B.Mask" "B.Paste")
			(net "GND")
		)
	)
	(footprint ""
		(layer "B.Cu")
		(at 77.47 -33.34766)
		(property "Reference" "R695"
			(at 0 0 0)
			(layer "B.SilkS")
			(hide yes)
			(effects
				(font
					(size 1.27 1.27)
				)
				(justify mirror)
			)
		)
		(property "Value" ""
			(at 0 0 0)
			(layer "B.Fab")
			(effects
				(font
					(size 1.27 1.27)
				)
				(justify mirror)
			)
		)
		(duplicate_pad_numbers_are_jumpers no)
		(fp_line
			(start -0.7874 -0.4064)
			(end -0.7874 0.4064)
			(stroke
				(width 0.1524)
				(type default)
			)
			(layer "B.SilkS")
		)
		(fp_line
			(start -0.7874 0.4064)
			(end 0.7874 0.4064)
			(stroke
				(width 0.1524)
				(type default)
			)
			(layer "B.SilkS")
		)
		(fp_line
			(start 0.7874 -0.4064)
			(end -0.7874 -0.4064)
			(stroke
				(width 0.1524)
				(type default)
			)
			(layer "B.SilkS")
		)
		(fp_line
			(start 0.7874 0.4064)
			(end 0.7874 -0.4064)
			(stroke
				(width 0.1524)
				(type default)
			)
			(layer "B.SilkS")
		)
		(fp_line
			(start -0.67945 -0.3048)
			(end -0.67945 0.3048)
			(stroke
				(width 0.1)
				(type default)
			)
			(layer "B.Fab")
		)
		(fp_line
			(start -0.67945 0.3048)
			(end -0.120396 0.3048)
			(stroke
				(width 0.1)
				(type default)
			)
			(layer "B.Fab")
		)
		(fp_line
			(start -0.12065 -0.3048)
			(end -0.67945 -0.3048)
			(stroke
				(width 0.1)
				(type default)
			)
			(layer "B.Fab")
		)
		(fp_line
			(start -0.12065 -0.2794)
			(end -0.12065 -0.3048)
			(stroke
				(width 0.1)
				(type default)
			)
			(layer "B.Fab")
		)
		(fp_line
			(start -0.120396 0.2794)
			(end 0.12065 0.2794)
			(stroke
				(width 0.1)
				(type default)
			)
			(layer "B.Fab")
		)
		(fp_line
			(start -0.120396 0.3048)
			(end -0.120396 0.2794)
			(stroke
				(width 0.1)
				(type default)
			)
			(layer "B.Fab")
		)
		(fp_line
			(start 0.12065 -0.305054)
			(end 0.12065 -0.2794)
			(stroke
				(width 0.1)
				(type default)
			)
			(layer "B.Fab")
		)
		(fp_line
			(start 0.12065 -0.2794)
			(end -0.12065 -0.2794)
			(stroke
				(width 0.1)
				(type default)
			)
			(layer "B.Fab")
		)
		(fp_line
			(start 0.12065 0.2794)
			(end 0.12065 0.3048)
			(stroke
				(width 0.1)
				(type default)
			)
			(layer "B.Fab")
		)
		(fp_line
			(start 0.12065 0.3048)
			(end 0.67945 0.3048)
			(stroke
				(width 0.1)
				(type default)
			)
			(layer "B.Fab")
		)
		(fp_line
			(start 0.67945 -0.305054)
			(end 0.12065 -0.305054)
			(stroke
				(width 0.1)
				(type default)
			)
			(layer "B.Fab")
		)
		(fp_line
			(start 0.67945 0.3048)
			(end 0.67945 -0.305054)
			(stroke
				(width 0.1)
				(type default)
			)
			(layer "B.Fab")
		)
		(pad "1" smd circle
			(at 0.40005 0 180)
			(size 0 0)
			(layers "B.Cu" "B.Mask" "B.Paste")
			(net "LED_POSTCODE_4")
		)
		(pad "2" smd circle
			(at -0.40005 0 180)
			(size 0 0)
			(layers "B.Cu" "B.Mask" "B.Paste")
			(net "LED_POSTCODE_4_R1")
		)
	)
)
